(kicad_pcb
	(version 20260206)
	(generator "pcbnew")
	(generator_version "10.0")
	(general
		(thickness 1.6)
		(legacy_teardrops no)
	)
	(paper "A4")
	(title_block
		(title "03242023_DA0F0TMBIJ0_F0T_Motherboard_J_brd_V01_OCP.brd")
		(comment 1 "Grand Teton / footprints 1886-1892 of 6105")
	)
	(layers
		(0 "F.Cu" signal "TOP")
		(4 "In1.Cu" signal "GND")
		(6 "In2.Cu" signal "IN1")
		(8 "In3.Cu" signal "GND1")
		(10 "In4.Cu" signal "IN2")
		(12 "In5.Cu" signal "GND2")
		(14 "In6.Cu" signal "IN3")
		(16 "In7.Cu" signal "GND3")
		(18 "In8.Cu" signal "VCC")
		(20 "In9.Cu" signal "VCC1")
		(22 "In10.Cu" signal "GND4")
		(24 "In11.Cu" signal "IN4")
		(26 "In12.Cu" signal "GND5")
		(28 "In13.Cu" signal "IN5")
		(30 "In14.Cu" signal "GND6")
		(32 "In15.Cu" signal "IN6")
		(34 "In16.Cu" signal "GND7")
		(2 "B.Cu" signal "BOTTOM")
		(9 "F.Adhes" user "F.Adhesive")
		(11 "B.Adhes" user "B.Adhesive")
		(13 "F.Paste" user "Package Geometry/Pastemask Top")
		(15 "B.Paste" user "Package Geometry/Pastemask Bottom")
		(5 "F.SilkS" user "Ref Des/Silkscreen Top")
		(7 "B.SilkS" user "Ref Des/Silkscreen Bottom")
		(1 "F.Mask" user "Board Geometry/Soldermask Top")
		(3 "B.Mask" user "Board Geometry/Soldermask Bottom")
		(17 "Dwgs.User" user "User.Drawings")
		(19 "Cmts.User" user "User.Comments")
		(21 "Eco1.User" user "User.Eco1")
		(23 "Eco2.User" user "User.Eco2")
		(25 "Edge.Cuts" user "Board Geometry/Outline")
		(27 "Margin" user)
		(31 "F.CrtYd" user "Package Geometry/Place Bound Top")
		(29 "B.CrtYd" user "Package Geometry/Place Bound Bottom")
		(35 "F.Fab" user "Ref Des/Assembly Top")
		(33 "B.Fab" user "Ref Des/Assembly Bottom")
	)
	(footprint ""
		(layer "F.Cu")
		(at 160.83788 -109.565948)
		(property "Reference" "R2847"
			(at 0 0 0)
			(layer "F.SilkS")
			(hide yes)
			(effects
				(font
					(size 1.27 1.27)
				)
			)
		)
		(property "Value" ""
			(at 0 0 0)
			(layer "F.Fab")
			(effects
				(font
					(size 1.27 1.27)
				)
			)
		)
		(duplicate_pad_numbers_are_jumpers no)
		(fp_line
			(start -0.7874 -0.4064)
			(end 0.7874 -0.4064)
			(stroke
				(width 0.1524)
				(type default)
			)
			(layer "F.SilkS")
		)
		(fp_line
			(start -0.7874 0.4064)
			(end -0.7874 -0.4064)
			(stroke
				(width 0.1524)
				(type default)
			)
			(layer "F.SilkS")
		)
		(fp_line
			(start 0.7874 -0.4064)
			(end 0.7874 0.4064)
			(stroke
				(width 0.1524)
				(type default)
			)
			(layer "F.SilkS")
		)
		(fp_line
			(start 0.7874 0.4064)
			(end -0.7874 0.4064)
			(stroke
				(width 0.1524)
				(type default)
			)
			(layer "F.SilkS")
		)
		(fp_line
			(start -0.67945 -0.305054)
			(end -0.12065 -0.305054)
			(stroke
				(width 0.1)
				(type default)
			)
			(layer "F.Fab")
		)
		(fp_line
			(start -0.67945 0.3048)
			(end -0.67945 -0.305054)
			(stroke
				(width 0.1)
				(type default)
			)
			(layer "F.Fab")
		)
		(fp_line
			(start -0.12065 -0.305054)
			(end -0.12065 -0.2794)
			(stroke
				(width 0.1)
				(type default)
			)
			(layer "F.Fab")
		)
		(fp_line
			(start -0.12065 -0.2794)
			(end 0.12065 -0.2794)
			(stroke
				(width 0.1)
				(type default)
			)
			(layer "F.Fab")
		)
		(fp_line
			(start -0.12065 0.2794)
			(end -0.12065 0.3048)
			(stroke
				(width 0.1)
				(type default)
			)
			(layer "F.Fab")
		)
		(fp_line
			(start -0.12065 0.3048)
			(end -0.67945 0.3048)
			(stroke
				(width 0.1)
				(type default)
			)
			(layer "F.Fab")
		)
		(fp_line
			(start 0.120396 0.2794)
			(end -0.12065 0.2794)
			(stroke
				(width 0.1)
				(type default)
			)
			(layer "F.Fab")
		)
		(fp_line
			(start 0.120396 0.3048)
			(end 0.120396 0.2794)
			(stroke
				(width 0.1)
				(type default)
			)
			(layer "F.Fab")
		)
		(fp_line
			(start 0.12065 -0.3048)
			(end 0.67945 -0.3048)
			(stroke
				(width 0.1)
				(type default)
			)
			(layer "F.Fab")
		)
		(fp_line
			(start 0.12065 -0.2794)
			(end 0.12065 -0.3048)
			(stroke
				(width 0.1)
				(type default)
			)
			(layer "F.Fab")
		)
		(fp_line
			(start 0.67945 -0.3048)
			(end 0.67945 0.3048)
			(stroke
				(width 0.1)
				(type default)
			)
			(layer "F.Fab")
		)
		(fp_line
			(start 0.67945 0.3048)
			(end 0.120396 0.3048)
			(stroke
				(width 0.1)
				(type default)
			)
			(layer "F.Fab")
		)
		(pad "1" smd circle
			(at -0.40005 0)
			(size 0 0)
			(layers "F.Cu" "F.Mask" "F.Paste")
			(net "RST_BMC_FROM_SWB_ISO_N")
		)
		(pad "2" smd circle
			(at 0.40005 0)
			(size 0 0)
			(layers "F.Cu" "F.Mask" "F.Paste")
			(net "RST_BMC_FROM_SWB_ISO_R_N")
		)
	)
	(footprint ""
		(layer "F.Cu")
		(at 107.2769 -255.0541 90)
		(property "Reference" "C279"
			(at 0 0 90)
			(layer "F.SilkS")
			(hide yes)
			(effects
				(font
					(size 1.27 1.27)
				)
			)
		)
		(property "Value" ""
			(at 0 0 90)
			(layer "F.Fab")
			(effects
				(font
					(size 1.27 1.27)
				)
			)
		)
		(duplicate_pad_numbers_are_jumpers no)
		(fp_line
			(start 0.7874 -0.4064)
			(end 0.7874 0.4064)
			(stroke
				(width 0.1524)
				(type default)
			)
			(layer "F.SilkS")
		)
		(fp_line
			(start -0.7874 -0.4064)
			(end 0.7874 -0.4064)
			(stroke
				(width 0.1524)
				(type default)
			)
			(layer "F.SilkS")
		)
		(fp_line
			(start 0.7874 0.4064)
			(end -0.7874 0.4064)
			(stroke
				(width 0.1524)
				(type default)
			)
			(layer "F.SilkS")
		)
		(fp_line
			(start -0.7874 0.4064)
			(end -0.7874 -0.4064)
			(stroke
				(width 0.1524)
				(type default)
			)
			(layer "F.SilkS")
		)
		(fp_line
			(start -0.12065 -0.305054)
			(end -0.12065 -0.2794)
			(stroke
				(width 0.1)
				(type default)
			)
			(layer "F.Fab")
		)
		(fp_line
			(start -0.67945 -0.305054)
			(end -0.12065 -0.305054)
			(stroke
				(width 0.1)
				(type default)
			)
			(layer "F.Fab")
		)
		(fp_line
			(start 0.67945 -0.3048)
			(end 0.67945 0.3048)
			(stroke
				(width 0.1)
				(type default)
			)
			(layer "F.Fab")
		)
		(fp_line
			(start 0.12065 -0.3048)
			(end 0.67945 -0.3048)
			(stroke
				(width 0.1)
				(type default)
			)
			(layer "F.Fab")
		)
		(fp_line
			(start 0.12065 -0.2794)
			(end 0.12065 -0.3048)
			(stroke
				(width 0.1)
				(type default)
			)
			(layer "F.Fab")
		)
		(fp_line
			(start -0.12065 -0.2794)
			(end 0.12065 -0.2794)
			(stroke
				(width 0.1)
				(type default)
			)
			(layer "F.Fab")
		)
		(fp_line
			(start 0.120396 0.2794)
			(end -0.12065 0.2794)
			(stroke
				(width 0.1)
				(type default)
			)
			(layer "F.Fab")
		)
		(fp_line
			(start -0.12065 0.2794)
			(end -0.12065 0.3048)
			(stroke
				(width 0.1)
				(type default)
			)
			(layer "F.Fab")
		)
		(fp_line
			(start 0.67945 0.3048)
			(end 0.120396 0.3048)
			(stroke
				(width 0.1)
				(type default)
			)
			(layer "F.Fab")
		)
		(fp_line
			(start 0.120396 0.3048)
			(end 0.120396 0.2794)
			(stroke
				(width 0.1)
				(type default)
			)
			(layer "F.Fab")
		)
		(fp_line
			(start -0.12065 0.3048)
			(end -0.67945 0.3048)
			(stroke
				(width 0.1)
				(type default)
			)
			(layer "F.Fab")
		)
		(fp_line
			(start -0.67945 0.3048)
			(end -0.67945 -0.305054)
			(stroke
				(width 0.1)
				(type default)
			)
			(layer "F.Fab")
		)
		(pad "1" smd circle
			(at -0.40005 0 90)
			(size 0 0)
			(layers "F.Cu" "F.Mask" "F.Paste")
			(net "PVCCIN_CPU1")
		)
		(pad "2" smd circle
			(at 0.40005 0 90)
			(size 0 0)
			(layers "F.Cu" "F.Mask" "F.Paste")
			(net "GND")
		)
	)
	(footprint ""
		(layer "F.Cu")
		(at 358.237282 -57.898792)
		(property "Reference" "R748"
			(at 0 0 0)
			(layer "F.SilkS")
			(hide yes)
			(effects
				(font
					(size 1.27 1.27)
				)
			)
		)
		(property "Value" ""
			(at 0 0 0)
			(layer "F.Fab")
			(effects
				(font
					(size 1.27 1.27)
				)
			)
		)
		(duplicate_pad_numbers_are_jumpers no)
		(fp_line
			(start -0.7874 -0.4064)
			(end 0.7874 -0.4064)
			(stroke
				(width 0.1524)
				(type default)
			)
			(layer "F.SilkS")
		)
		(fp_line
			(start -0.7874 0.4064)
			(end -0.7874 -0.4064)
			(stroke
				(width 0.1524)
				(type default)
			)
			(layer "F.SilkS")
		)
		(fp_line
			(start 0.7874 -0.4064)
			(end 0.7874 0.4064)
			(stroke
				(width 0.1524)
				(type default)
			)
			(layer "F.SilkS")
		)
		(fp_line
			(start 0.7874 0.4064)
			(end -0.7874 0.4064)
			(stroke
				(width 0.1524)
				(type default)
			)
			(layer "F.SilkS")
		)
		(fp_line
			(start -0.67945 -0.305054)
			(end -0.12065 -0.305054)
			(stroke
				(width 0.1)
				(type default)
			)
			(layer "F.Fab")
		)
		(fp_line
			(start -0.67945 0.3048)
			(end -0.67945 -0.305054)
			(stroke
				(width 0.1)
				(type default)
			)
			(layer "F.Fab")
		)
		(fp_line
			(start -0.12065 -0.305054)
			(end -0.12065 -0.2794)
			(stroke
				(width 0.1)
				(type default)
			)
			(layer "F.Fab")
		)
		(fp_line
			(start -0.12065 -0.2794)
			(end 0.12065 -0.2794)
			(stroke
				(width 0.1)
				(type default)
			)
			(layer "F.Fab")
		)
		(fp_line
			(start -0.12065 0.2794)
			(end -0.12065 0.3048)
			(stroke
				(width 0.1)
				(type default)
			)
			(layer "F.Fab")
		)
		(fp_line
			(start -0.12065 0.3048)
			(end -0.67945 0.3048)
			(stroke
				(width 0.1)
				(type default)
			)
			(layer "F.Fab")
		)
		(fp_line
			(start 0.120396 0.2794)
			(end -0.12065 0.2794)
			(stroke
				(width 0.1)
				(type default)
			)
			(layer "F.Fab")
		)
		(fp_line
			(start 0.120396 0.3048)
			(end 0.120396 0.2794)
			(stroke
				(width 0.1)
				(type default)
			)
			(layer "F.Fab")
		)
		(fp_line
			(start 0.12065 -0.3048)
			(end 0.67945 -0.3048)
			(stroke
				(width 0.1)
				(type default)
			)
			(layer "F.Fab")
		)
		(fp_line
			(start 0.12065 -0.2794)
			(end 0.12065 -0.3048)
			(stroke
				(width 0.1)
				(type default)
			)
			(layer "F.Fab")
		)
		(fp_line
			(start 0.67945 -0.3048)
			(end 0.67945 0.3048)
			(stroke
				(width 0.1)
				(type default)
			)
			(layer "F.Fab")
		)
		(fp_line
			(start 0.67945 0.3048)
			(end 0.120396 0.3048)
			(stroke
				(width 0.1)
				(type default)
			)
			(layer "F.Fab")
		)
		(pad "1" smd circle
			(at -0.40005 0)
			(size 0 0)
			(layers "F.Cu" "F.Mask" "F.Paste")
			(net "P1V05_PCH_AUX")
		)
		(pad "2" smd circle
			(at 0.40005 0)
			(size 0 0)
			(layers "F.Cu" "F.Mask" "F.Paste")
			(net "JTAG_DBP_TDI_PCH")
		)
	)
	(footprint ""
		(layer "F.Cu")
		(at 406.43937 -408.517344 -90)
		(property "Reference" "C892"
			(at 0 0 270)
			(layer "F.SilkS")
			(hide yes)
			(effects
				(font
					(size 1.27 1.27)
				)
			)
		)
		(property "Value" ""
			(at 0 0 270)
			(layer "F.Fab")
			(effects
				(font
					(size 1.27 1.27)
				)
			)
		)
		(duplicate_pad_numbers_are_jumpers no)
		(fp_line
			(start -0.299974 0.150114)
			(end -0.299974 -0.150114)
			(stroke
				(width 0.1)
				(type default)
			)
			(layer "F.Fab")
		)
		(fp_line
			(start 0.299974 0.150114)
			(end -0.299974 0.150114)
			(stroke
				(width 0.1)
				(type default)
			)
			(layer "F.Fab")
		)
		(fp_line
			(start -0.299974 -0.150114)
			(end 0.299974 -0.150114)
			(stroke
				(width 0.1)
				(type default)
			)
			(layer "F.Fab")
		)
		(fp_line
			(start 0.299974 -0.150114)
			(end 0.299974 0.150114)
			(stroke
				(width 0.1)
				(type default)
			)
			(layer "F.Fab")
		)
		(pad "1" smd rect
			(at -0.2667 0 270)
			(size 0.3048 0.381)
			(layers "F.Cu" "F.Mask" "F.Paste")
			(net "P5E_CPU0_PE3_TX_C_DN<4>")
		)
		(pad "2" smd rect
			(at 0.2667 0 270)
			(size 0.3048 0.381)
			(layers "F.Cu" "F.Mask" "F.Paste")
			(net "P5E_CPU0_PE3_TX_DN<4>")
		)
	)
	(footprint ""
		(layer "F.Cu")
		(at 28.578048 -69.7992)
		(property "Reference" "R4753"
			(at 0 0 0)
			(layer "F.SilkS")
			(hide yes)
			(effects
				(font
					(size 1.27 1.27)
				)
			)
		)
		(property "Value" ""
			(at 0 0 0)
			(layer "F.Fab")
			(effects
				(font
					(size 1.27 1.27)
				)
			)
		)
		(duplicate_pad_numbers_are_jumpers no)
		(fp_line
			(start -0.7874 -0.4064)
			(end 0.7874 -0.4064)
			(stroke
				(width 0.1524)
				(type default)
			)
			(layer "F.SilkS")
		)
		(fp_line
			(start -0.7874 0.4064)
			(end -0.7874 -0.4064)
			(stroke
				(width 0.1524)
				(type default)
			)
			(layer "F.SilkS")
		)
		(fp_line
			(start 0.7874 -0.4064)
			(end 0.7874 0.4064)
			(stroke
				(width 0.1524)
				(type default)
			)
			(layer "F.SilkS")
		)
		(fp_line
			(start 0.7874 0.4064)
			(end -0.7874 0.4064)
			(stroke
				(width 0.1524)
				(type default)
			)
			(layer "F.SilkS")
		)
		(fp_line
			(start -0.67945 -0.305054)
			(end -0.12065 -0.305054)
			(stroke
				(width 0.1)
				(type default)
			)
			(layer "F.Fab")
		)
		(fp_line
			(start -0.67945 0.3048)
			(end -0.67945 -0.305054)
			(stroke
				(width 0.1)
				(type default)
			)
			(layer "F.Fab")
		)
		(fp_line
			(start -0.12065 -0.305054)
			(end -0.12065 -0.2794)
			(stroke
				(width 0.1)
				(type default)
			)
			(layer "F.Fab")
		)
		(fp_line
			(start -0.12065 -0.2794)
			(end 0.12065 -0.2794)
			(stroke
				(width 0.1)
				(type default)
			)
			(layer "F.Fab")
		)
		(fp_line
			(start -0.12065 0.2794)
			(end -0.12065 0.3048)
			(stroke
				(width 0.1)
				(type default)
			)
			(layer "F.Fab")
		)
		(fp_line
			(start -0.12065 0.3048)
			(end -0.67945 0.3048)
			(stroke
				(width 0.1)
				(type default)
			)
			(layer "F.Fab")
		)
		(fp_line
			(start 0.120396 0.2794)
			(end -0.12065 0.2794)
			(stroke
				(width 0.1)
				(type default)
			)
			(layer "F.Fab")
		)
		(fp_line
			(start 0.120396 0.3048)
			(end 0.120396 0.2794)
			(stroke
				(width 0.1)
				(type default)
			)
			(layer "F.Fab")
		)
		(fp_line
			(start 0.12065 -0.3048)
			(end 0.67945 -0.3048)
			(stroke
				(width 0.1)
				(type default)
			)
			(layer "F.Fab")
		)
		(fp_line
			(start 0.12065 -0.2794)
			(end 0.12065 -0.3048)
			(stroke
				(width 0.1)
				(type default)
			)
			(layer "F.Fab")
		)
		(fp_line
			(start 0.67945 -0.3048)
			(end 0.67945 0.3048)
			(stroke
				(width 0.1)
				(type default)
			)
			(layer "F.Fab")
		)
		(fp_line
			(start 0.67945 0.3048)
			(end 0.120396 0.3048)
			(stroke
				(width 0.1)
				(type default)
			)
			(layer "F.Fab")
		)
		(pad "1" smd circle
			(at -0.40005 0)
			(size 0 0)
			(layers "F.Cu" "F.Mask" "F.Paste")
			(net "HP_LVC3_OCP_V3_2_PRSNT2_N_R")
		)
		(pad "2" smd circle
			(at 0.40005 0)
			(size 0 0)
			(layers "F.Cu" "F.Mask" "F.Paste")
			(net "HP_LVC3_OCP_V3_2_PRSNT2_PLD_N")
		)
	)
	(footprint ""
		(layer "F.Cu")
		(at 142.486126 -343.018872 -90)
		(property "Reference" "PC483_P1_8"
			(at 0 0 270)
			(layer "F.SilkS")
			(hide yes)
			(effects
				(font
					(size 1.27 1.27)
				)
			)
		)
		(property "Value" ""
			(at 0 0 270)
			(layer "F.Fab")
			(effects
				(font
					(size 1.27 1.27)
				)
			)
		)
		(duplicate_pad_numbers_are_jumpers no)
		(fp_line
			(start -0.7874 0.4064)
			(end -0.7874 -0.4064)
			(stroke
				(width 0.1524)
				(type default)
			)
			(layer "F.SilkS")
		)
		(fp_line
			(start 0.7874 0.4064)
			(end -0.7874 0.4064)
			(stroke
				(width 0.1524)
				(type default)
			)
			(layer "F.SilkS")
		)
		(fp_line
			(start -0.7874 -0.4064)
			(end 0.7874 -0.4064)
			(stroke
				(width 0.1524)
				(type default)
			)
			(layer "F.SilkS")
		)
		(fp_line
			(start 0.7874 -0.4064)
			(end 0.7874 0.4064)
			(stroke
				(width 0.1524)
				(type default)
			)
			(layer "F.SilkS")
		)
		(fp_line
			(start -0.67945 0.3048)
			(end -0.67945 -0.305054)
			(stroke
				(width 0.1)
				(type default)
			)
			(layer "F.Fab")
		)
		(fp_line
			(start -0.12065 0.3048)
			(end -0.67945 0.3048)
			(stroke
				(width 0.1)
				(type default)
			)
			(layer "F.Fab")
		)
		(fp_line
			(start 0.120396 0.3048)
			(end 0.120396 0.2794)
			(stroke
				(width 0.1)
				(type default)
			)
			(layer "F.Fab")
		)
		(fp_line
			(start 0.67945 0.3048)
			(end 0.120396 0.3048)
			(stroke
				(width 0.1)
				(type default)
			)
			(layer "F.Fab")
		)
		(fp_line
			(start -0.12065 0.2794)
			(end -0.12065 0.3048)
			(stroke
				(width 0.1)
				(type default)
			)
			(layer "F.Fab")
		)
		(fp_line
			(start 0.120396 0.2794)
			(end -0.12065 0.2794)
			(stroke
				(width 0.1)
				(type default)
			)
			(layer "F.Fab")
		)
		(fp_line
			(start -0.12065 -0.2794)
			(end 0.12065 -0.2794)
			(stroke
				(width 0.1)
				(type default)
			)
			(layer "F.Fab")
		)
		(fp_line
			(start 0.12065 -0.2794)
			(end 0.12065 -0.3048)
			(stroke
				(width 0.1)
				(type default)
			)
			(layer "F.Fab")
		)
		(fp_line
			(start 0.12065 -0.3048)
			(end 0.67945 -0.3048)
			(stroke
				(width 0.1)
				(type default)
			)
			(layer "F.Fab")
		)
		(fp_line
			(start 0.67945 -0.3048)
			(end 0.67945 0.3048)
			(stroke
				(width 0.1)
				(type default)
			)
			(layer "F.Fab")
		)
		(fp_line
			(start -0.67945 -0.305054)
			(end -0.12065 -0.305054)
			(stroke
				(width 0.1)
				(type default)
			)
			(layer "F.Fab")
		)
		(fp_line
			(start -0.12065 -0.305054)
			(end -0.12065 -0.2794)
			(stroke
				(width 0.1)
				(type default)
			)
			(layer "F.Fab")
		)
		(pad "1" smd circle
			(at -0.40005 0 270)
			(size 0 0)
			(layers "F.Cu" "F.Mask" "F.Paste")
			(net "SW_P12V_PVCCIN_CPU1_FLT")
		)
		(pad "2" smd circle
			(at 0.40005 0 270)
			(size 0 0)
			(layers "F.Cu" "F.Mask" "F.Paste")
			(net "GND")
		)
	)
	(footprint ""
		(layer "F.Cu")
		(at 86.868 -65.173098 -90)
		(property "Reference" "R1044"
			(at 0 0 270)
			(layer "F.SilkS")
			(hide yes)
			(effects
				(font
					(size 1.27 1.27)
				)
			)
		)
		(property "Value" ""
			(at 0 0 270)
			(layer "F.Fab")
			(effects
				(font
					(size 1.27 1.27)
				)
			)
		)
		(duplicate_pad_numbers_are_jumpers no)
		(fp_line
			(start -0.7874 0.4064)
			(end -0.7874 -0.4064)
			(stroke
				(width 0.1524)
				(type default)
			)
			(layer "F.SilkS")
		)
		(fp_line
			(start 0.7874 0.4064)
			(end -0.7874 0.4064)
			(stroke
				(width 0.1524)
				(type default)
			)
			(layer "F.SilkS")
		)
		(fp_line
			(start -0.7874 -0.4064)
			(end 0.7874 -0.4064)
			(stroke
				(width 0.1524)
				(type default)
			)
			(layer "F.SilkS")
		)
		(fp_line
			(start 0.7874 -0.4064)
			(end 0.7874 0.4064)
			(stroke
				(width 0.1524)
				(type default)
			)
			(layer "F.SilkS")
		)
		(fp_line
			(start -0.67945 0.3048)
			(end -0.67945 -0.305054)
			(stroke
				(width 0.1)
				(type default)
			)
			(layer "F.Fab")
		)
		(fp_line
			(start -0.12065 0.3048)
			(end -0.67945 0.3048)
			(stroke
				(width 0.1)
				(type default)
			)
			(layer "F.Fab")
		)
		(fp_line
			(start 0.120396 0.3048)
			(end 0.120396 0.2794)
			(stroke
				(width 0.1)
				(type default)
			)
			(layer "F.Fab")
		)
		(fp_line
			(start 0.67945 0.3048)
			(end 0.120396 0.3048)
			(stroke
				(width 0.1)
				(type default)
			)
			(layer "F.Fab")
		)
		(fp_line
			(start -0.12065 0.2794)
			(end -0.12065 0.3048)
			(stroke
				(width 0.1)
				(type default)
			)
			(layer "F.Fab")
		)
		(fp_line
			(start 0.120396 0.2794)
			(end -0.12065 0.2794)
			(stroke
				(width 0.1)
				(type default)
			)
			(layer "F.Fab")
		)
		(fp_line
			(start -0.12065 -0.2794)
			(end 0.12065 -0.2794)
			(stroke
				(width 0.1)
				(type default)
			)
			(layer "F.Fab")
		)
		(fp_line
			(start 0.12065 -0.2794)
			(end 0.12065 -0.3048)
			(stroke
				(width 0.1)
				(type default)
			)
			(layer "F.Fab")
		)
		(fp_line
			(start 0.12065 -0.3048)
			(end 0.67945 -0.3048)
			(stroke
				(width 0.1)
				(type default)
			)
			(layer "F.Fab")
		)
		(fp_line
			(start 0.67945 -0.3048)
			(end 0.67945 0.3048)
			(stroke
				(width 0.1)
				(type default)
			)
			(layer "F.Fab")
		)
		(fp_line
			(start -0.67945 -0.305054)
			(end -0.12065 -0.305054)
			(stroke
				(width 0.1)
				(type default)
			)
			(layer "F.Fab")
		)
		(fp_line
			(start -0.12065 -0.305054)
			(end -0.12065 -0.2794)
			(stroke
				(width 0.1)
				(type default)
			)
			(layer "F.Fab")
		)
		(pad "1" smd circle
			(at -0.40005 0 270)
			(size 0 0)
			(layers "F.Cu" "F.Mask" "F.Paste")
			(net "LED_PWRGD_CPUPWRGD_GTL")
		)
		(pad "2" smd circle
			(at 0.40005 0 270)
			(size 0 0)
			(layers "F.Cu" "F.Mask" "F.Paste")
			(net "P3V3_AUX")
		)
	)
)
